#ISCELL
  mstr_misc dns *
  *
#ISCELL
  mstr_symbols design_note *
  *
#ISCELL
  mstr_symbols intel_corp_bpage *
  *
#ISCELL
  mstr_standard offpage *
  page209_i1
#CELL
  mstr_discrete res *
  page209_i10
#CELL
  mstr_discrete res *
  page209_i11
#ISCELL
  mstr_symbols gnd *
  page209_i12
#ISCELL
  mstr_standard offpage *
  page209_i13
#ISCELL
  mstr_standard offpage *
  page209_i14
#CELL
  mstr_discrete res *
  page209_i15
#CELL
  mstr_discrete cap *
  page209_i16
#CELL
  dev_discrete cap_a *
  page209_i17
#CELL
  mstr_discrete cap *
  page209_i18
#ISCELL
  mstr_symbols pvccin_cpu1 *
  page209_i19
#ISCELL
  mstr_standard offpage *
  page209_i2
#CELL
  mstr_discrete cap *
  page209_i20
#CELL
  mstr_discrete cap *
  page209_i22
#ISCELL
  mstr_symbols vcc_core *
  page209_i23
#CELL
  mstr_discrete res *
  page209_i3
#ISCELL
  mstr_symbols gnd *
  page209_i34
#CELL
  mstr_discrete capp *
  page209_i35
#ISCELL
  mstr_symbols gnd *
  page209_i36
#CELL
  mstr_discrete capp *
  page209_i37
#CELL
  mstr_discrete capp *
  page209_i38
#ISCELL
  mstr_symbols gnd *
  page209_i4
#ISCELL
  mstr_symbols gnd *
  page209_i41
#CELL
  dev_discrete cap_a *
  page209_i42
#ISCELL
  mstr_symbols pvccin_cpu1 *
  page209_i43
#ISCELL
  mstr_standard offpage *
  page209_i44
#ISCELL
  mstr_symbols vcc_core *
  page209_i45
#ISCELL
  mstr_standard offpage *
  page209_i49
#CELL
  mstr_discrete cap *
  page209_i5
#ISCELL
  mstr_symbols p12v_stby *
  page209_i53
#ISCELL
  mstr_symbols p5v_stby *
  page209_i54
#CELL
  dev_discrete cap_a *
  page209_i55
#CELL
  mstr_discrete ir354xx *
  page209_i56
#ISCELL
  mstr_standard offpage *
  page209_i57
#ISCELL
  mstr_standard offpage *
  page209_i58
#CELL
  mstr_discrete res *
  page209_i59
#ISCELL
  mstr_symbols gnd *
  page209_i60
#CELL
  dev_discrete cap_a *
  page209_i62
#ISCELL
  mstr_symbols gnd *
  page209_i63
#ISCELL
  mstr_symbols gnd *
  page209_i65
#CELL
  mstr_discrete cap *
  page209_i67
#ISCELL
  mstr_symbols gnd *
  page209_i68
#CELL
  mstr_discrete cap *
  page209_i7
#CELL
  mstr_discrete cap *
  page209_i73
#CELL
  mstr_discrete res *
  page209_i75
#CELL
  mstr_discrete res *
  page209_i79
#CELL
  mstr_discrete cap *
  page209_i8
#CELL
  w_hdl ind-120nh-30-gp *
  page209_i80
#CELL
  w_hdl ind-80nh-1-gp *
  page209_i81
#CELL
  w_hdl sc1u10v2kx-4-gp *
  page209_i89
#CELL
  mstr_discrete res *
  page209_i9
#CELL
  w_hdl 1r3f-gp *
  page209_i90
